(kicad_pcb
	(version 20260206)
	(generator "pcbnew")
	(generator_version "10.0")
	(general
		(thickness 1.6)
		(legacy_teardrops no)
	)
	(paper "A4")
	(title_block
		(title "timecard-production-celestica-r4006 — R4006-B0001-02_R01.brd")
		(comment 1 "Time Appliance Project (Time Card) / footprints 73-77 of 1113")
	)
	(layers
		(0 "F.Cu" signal "TOP")
		(4 "In1.Cu" signal "L02_GND1")
		(6 "In2.Cu" signal "L03_SIG1")
		(8 "In3.Cu" signal "L04_GND2")
		(10 "In4.Cu" signal "L05_VCC1")
		(12 "In5.Cu" signal "L06_VCC2")
		(14 "In6.Cu" signal "L07_GND3")
		(16 "In7.Cu" signal "L08_SIG2")
		(18 "In8.Cu" signal "L09_GND4")
		(2 "B.Cu" signal "BOTTOM")
		(9 "F.Adhes" user "F.Adhesive")
		(11 "B.Adhes" user "B.Adhesive")
		(13 "F.Paste" user "Package Geometry/Pastemask Top")
		(15 "B.Paste" user "Package Geometry/Pastemask Bottom")
		(5 "F.SilkS" user "Ref Des/Silkscreen Top")
		(7 "B.SilkS" user "Ref Des/Silkscreen Bottom")
		(1 "F.Mask" user "Board Geometry/Soldermask Top")
		(3 "B.Mask" user "Board Geometry/Soldermask Bottom")
		(17 "Dwgs.User" user "User.Drawings")
		(19 "Cmts.User" user "User.Comments")
		(21 "Eco1.User" user "User.Eco1")
		(23 "Eco2.User" user "User.Eco2")
		(25 "Edge.Cuts" user "Board Geometry/Outline")
		(27 "Margin" user)
		(31 "F.CrtYd" user "Package Geometry/Place Bound Top")
		(29 "B.CrtYd" user "Package Geometry/Place Bound Bottom")
		(35 "F.Fab" user "Ref Des/Assembly Top")
		(33 "B.Fab" user "Ref Des/Assembly Bottom")
	)
	(footprint ""
		(layer "F.Cu")
		(at 145.8214 -91.8718 180)
		(property "Reference" "R7"
			(at 0.2794 -8.47217 0)
			(unlocked yes)
			(layer "F.SilkS")
			(effects
				(font
					(size 0.7874 0.5842)
					(thickness 0.1524)
				)
			)
		)
		(property "Value" "VAL*"
			(at 0.02032 2.13233 180)
			(unlocked yes)
			(layer "F.Fab")
			(hide yes)
			(effects
				(font
					(size 0.7874 0.5842)
					(thickness 0.1524)
				)
			)
		)
		(property "Device Type" "RESISTOR-G155-100R0-J0,0OHM,-"
			(at 0.008382 1.210564 180)
			(unlocked yes)
			(layer "F.Fab")
			(hide yes)
			(effects
				(font
					(size 0.7874 0.5842)
					(thickness 0.1524)
				)
			)
		)
		(property "User Part Number" "PARTNUM*"
			(at 0.02032 4.024884 180)
			(unlocked yes)
			(layer "Cmts.User")
			(hide yes)
			(effects
				(font
					(size 0.7874 0.5842)
					(thickness 0.1524)
				)
			)
		)
		(property "Tolerance" "TOL*"
			(at 0.044704 3.05435 180)
			(unlocked yes)
			(layer "Cmts.User")
			(hide yes)
			(effects
				(font
					(size 0.7874 0.5842)
					(thickness 0.1524)
				)
			)
		)
		(duplicate_pad_numbers_are_jumpers no)
		(fp_line
			(start 1.143 0.5588)
			(end 1.143 -0.5588)
			(stroke
				(width 0.1)
				(type default)
			)
			(layer "F.SilkS")
		)
		(fp_line
			(start 1.143 -0.5588)
			(end -1.143 -0.5588)
			(stroke
				(width 0.1)
				(type default)
			)
			(layer "F.SilkS")
		)
		(fp_line
			(start -1.143 0.5588)
			(end 1.143 0.5588)
			(stroke
				(width 0.1)
				(type default)
			)
			(layer "F.SilkS")
		)
		(fp_line
			(start -1.143 -0.5588)
			(end -1.143 0.5588)
			(stroke
				(width 0.1)
				(type default)
			)
			(layer "F.SilkS")
		)
		(fp_rect
			(start 1.143 -0.5588)
			(end -1.143 0.5588)
			(stroke
				(width 0)
				(type default)
			)
			(fill no)
			(layer "F.CrtYd")
		)
		(fp_line
			(start 0.508 0.3048)
			(end 0.508 -0.3048)
			(stroke
				(width 0.1)
				(type default)
			)
			(layer "F.Fab")
		)
		(fp_line
			(start 0.508 -0.3048)
			(end -0.508 -0.3048)
			(stroke
				(width 0.1)
				(type default)
			)
			(layer "F.Fab")
		)
		(fp_line
			(start -0.508 0.3048)
			(end 0.508 0.3048)
			(stroke
				(width 0.1)
				(type default)
			)
			(layer "F.Fab")
		)
		(fp_line
			(start -0.508 -0.3048)
			(end -0.508 0.3048)
			(stroke
				(width 0.1)
				(type default)
			)
			(layer "F.Fab")
		)
		(pad "1" smd rect
			(at -0.5334 0 180)
			(size 0.7112 0.6096)
			(layers "F.Cu" "F.Mask" "F.Paste")
			(net "SG")
		)
		(pad "2" smd rect
			(at 0.5334 0 180)
			(size 0.7112 0.6096)
			(layers "F.Cu" "F.Mask" "F.Paste")
			(net "UNNAMED_15_MP5022CGQVZQFN22_I_2")
		)
		(zone
			(layer "F.Cu")
			(hatch none 0.5)
			(connect_pads
				(clearance 0)
			)
			(min_thickness 0.25)
			(keepout
				(tracks allowed)
				(vias not_allowed)
				(pads allowed)
				(copperpour not_allowed)
				(footprints allowed)
			)
			(placement
				(enabled no)
				(sheetname "")
			)
			(fill
				(thermal_gap 0.5)
				(thermal_bridge_width 0.5)
				(island_removal_mode 0)
			)
			(polygon
				(pts
					(xy 145.7452 -91.567) (xy 145.8976 -91.567) (xy 145.8976 -92.1766) (xy 145.7452 -92.1766)
				)
			)
		)
	)
	(footprint ""
		(layer "F.Cu")
		(at 98.044 -96.774 180)
		(property "Reference" "R448"
			(at 1.143 2.75463 0)
			(unlocked yes)
			(layer "F.SilkS")
			(effects
				(font
					(size 0.7874 0.5842)
					(thickness 0.1524)
				)
			)
		)
		(property "Value" "VAL*"
			(at 0.02032 2.13233 180)
			(unlocked yes)
			(layer "F.Fab")
			(hide yes)
			(effects
				(font
					(size 0.7874 0.5842)
					(thickness 0.1524)
				)
			)
		)
		(property "Tolerance" "TOL*"
			(at 0.044704 3.05435 180)
			(unlocked yes)
			(layer "Cmts.User")
			(hide yes)
			(effects
				(font
					(size 0.7874 0.5842)
					(thickness 0.1524)
				)
			)
		)
		(property "User Part Number" "PARTNUM*"
			(at 0.02032 4.024884 180)
			(unlocked yes)
			(layer "Cmts.User")
			(hide yes)
			(effects
				(font
					(size 0.7874 0.5842)
					(thickness 0.1524)
				)
			)
		)
		(property "Device Type" "RESISTOR-G155-133R0-01,33OHM,1%"
			(at 0.008382 1.210564 180)
			(unlocked yes)
			(layer "F.Fab")
			(hide yes)
			(effects
				(font
					(size 0.7874 0.5842)
					(thickness 0.1524)
				)
			)
		)
		(duplicate_pad_numbers_are_jumpers no)
		(fp_line
			(start 1.143 0.5588)
			(end 1.143 -0.5588)
			(stroke
				(width 0.1)
				(type default)
			)
			(layer "F.SilkS")
		)
		(fp_line
			(start 1.143 -0.5588)
			(end -1.143 -0.5588)
			(stroke
				(width 0.1)
				(type default)
			)
			(layer "F.SilkS")
		)
		(fp_line
			(start -1.143 0.5588)
			(end 1.143 0.5588)
			(stroke
				(width 0.1)
				(type default)
			)
			(layer "F.SilkS")
		)
		(fp_line
			(start -1.143 -0.5588)
			(end -1.143 0.5588)
			(stroke
				(width 0.1)
				(type default)
			)
			(layer "F.SilkS")
		)
		(fp_poly
			(pts
				(xy -1.143 0.5588) (xy 1.143 0.5588) (xy 1.143 -0.5588) (xy -1.143 -0.5588)
			)
			(stroke
				(width 0)
				(type default)
			)
			(fill no)
			(layer "F.CrtYd")
		)
		(fp_line
			(start 0.508 0.3048)
			(end 0.508 -0.3048)
			(stroke
				(width 0.1)
				(type default)
			)
			(layer "F.Fab")
		)
		(fp_line
			(start 0.508 -0.3048)
			(end -0.508 -0.3048)
			(stroke
				(width 0.1)
				(type default)
			)
			(layer "F.Fab")
		)
		(fp_line
			(start -0.508 0.3048)
			(end 0.508 0.3048)
			(stroke
				(width 0.1)
				(type default)
			)
			(layer "F.Fab")
		)
		(fp_line
			(start -0.508 -0.3048)
			(end -0.508 0.3048)
			(stroke
				(width 0.1)
				(type default)
			)
			(layer "F.Fab")
		)
		(pad "1" smd rect
			(at -0.5334 0 180)
			(size 0.7112 0.6096)
			(layers "F.Cu" "F.Mask" "F.Paste")
			(net "MUX1_SEL")
		)
		(pad "2" smd rect
			(at 0.5334 0 180)
			(size 0.7112 0.6096)
			(layers "F.Cu" "F.Mask" "F.Paste")
			(net "FPGA_OUT_MUX1_SEL")
		)
		(zone
			(layer "F.Cu")
			(hatch none 0.5)
			(connect_pads
				(clearance 0)
			)
			(min_thickness 0.25)
			(keepout
				(tracks allowed)
				(vias not_allowed)
				(pads allowed)
				(copperpour not_allowed)
				(footprints allowed)
			)
			(placement
				(enabled no)
				(sheetname "")
			)
			(fill
				(thermal_gap 0.5)
				(thermal_bridge_width 0.5)
				(island_removal_mode 0)
			)
			(polygon
				(pts
					(xy 98.1202 -97.0788) (xy 97.9678 -97.0788) (xy 97.9678 -96.4692) (xy 98.1202 -96.4692)
				)
			)
		)
		(zone
			(layer "F.Cu")
			(hatch none 0.5)
			(connect_pads
				(clearance 0)
			)
			(min_thickness 0.25)
			(keepout
				(tracks not_allowed)
				(vias allowed)
				(pads allowed)
				(copperpour not_allowed)
				(footprints allowed)
			)
			(placement
				(enabled no)
				(sheetname "")
			)
			(fill
				(thermal_gap 0.5)
				(thermal_bridge_width 0.5)
				(island_removal_mode 0)
			)
			(polygon
				(pts
					(xy 98.1202 -97.0788) (xy 97.9678 -97.0788) (xy 97.9678 -96.4692) (xy 98.1202 -96.4692)
				)
			)
		)
	)
	(footprint ""
		(layer "F.Cu")
		(at 30.34538 -19.14144 180)
		(property "Reference" "R1992"
			(at 0.508 4.91363 0)
			(unlocked yes)
			(layer "F.SilkS")
			(effects
				(font
					(size 0.7874 0.5842)
					(thickness 0.1524)
				)
			)
		)
		(property "Value" "VAL*"
			(at 0.02032 2.13233 180)
			(unlocked yes)
			(layer "F.Fab")
			(hide yes)
			(effects
				(font
					(size 0.7874 0.5842)
					(thickness 0.1524)
				)
			)
		)
		(property "Tolerance" "TOL*"
			(at 0.044704 3.05435 180)
			(unlocked yes)
			(layer "Cmts.User")
			(hide yes)
			(effects
				(font
					(size 0.7874 0.5842)
					(thickness 0.1524)
				)
			)
		)
		(property "User Part Number" "PARTNUM*"
			(at 0.02032 4.024884 180)
			(unlocked yes)
			(layer "Cmts.User")
			(hide yes)
			(effects
				(font
					(size 0.7874 0.5842)
					(thickness 0.1524)
				)
			)
		)
		(property "Device Type" "RESISTOR-G155-14701-01,4.7KOHMA"
			(at 0.008382 1.210564 180)
			(unlocked yes)
			(layer "F.Fab")
			(hide yes)
			(effects
				(font
					(size 0.7874 0.5842)
					(thickness 0.1524)
				)
			)
		)
		(duplicate_pad_numbers_are_jumpers no)
		(fp_line
			(start 1.143 0.5588)
			(end 1.143 -0.5588)
			(stroke
				(width 0.1)
				(type default)
			)
			(layer "F.SilkS")
		)
		(fp_line
			(start 1.143 -0.5588)
			(end -1.143 -0.5588)
			(stroke
				(width 0.1)
				(type default)
			)
			(layer "F.SilkS")
		)
		(fp_line
			(start -1.143 0.5588)
			(end 1.143 0.5588)
			(stroke
				(width 0.1)
				(type default)
			)
			(layer "F.SilkS")
		)
		(fp_line
			(start -1.143 -0.5588)
			(end -1.143 0.5588)
			(stroke
				(width 0.1)
				(type default)
			)
			(layer "F.SilkS")
		)
		(fp_rect
			(start 1.143 -0.5588)
			(end -1.143 0.5588)
			(stroke
				(width 0)
				(type default)
			)
			(fill no)
			(layer "F.CrtYd")
		)
		(fp_line
			(start 0.508 0.3048)
			(end 0.508 -0.3048)
			(stroke
				(width 0.1)
				(type default)
			)
			(layer "F.Fab")
		)
		(fp_line
			(start 0.508 -0.3048)
			(end -0.508 -0.3048)
			(stroke
				(width 0.1)
				(type default)
			)
			(layer "F.Fab")
		)
		(fp_line
			(start -0.508 0.3048)
			(end 0.508 0.3048)
			(stroke
				(width 0.1)
				(type default)
			)
			(layer "F.Fab")
		)
		(fp_line
			(start -0.508 -0.3048)
			(end -0.508 0.3048)
			(stroke
				(width 0.1)
				(type default)
			)
			(layer "F.Fab")
		)
		(pad "1" smd rect
			(at -0.5334 0 180)
			(size 0.7112 0.6096)
			(layers "F.Cu" "F.Mask" "F.Paste")
			(net "XP3R3V_FPGA")
		)
		(pad "2" smd rect
			(at 0.5334 0 180)
			(size 0.7112 0.6096)
			(layers "F.Cu" "F.Mask" "F.Paste")
			(net "SN_EEPROM_WP")
		)
		(zone
			(layer "F.Cu")
			(hatch none 0.5)
			(connect_pads
				(clearance 0)
			)
			(min_thickness 0.25)
			(keepout
				(tracks allowed)
				(vias not_allowed)
				(pads allowed)
				(copperpour not_allowed)
				(footprints allowed)
			)
			(placement
				(enabled no)
				(sheetname "")
			)
			(fill
				(thermal_gap 0.5)
				(thermal_bridge_width 0.5)
				(island_removal_mode 0)
			)
			(polygon
				(pts
					(xy 30.26918 -18.83664) (xy 30.42158 -18.83664) (xy 30.42158 -19.44624) (xy 30.26918 -19.44624)
				)
			)
		)
	)
	(footprint ""
		(layer "F.Cu")
		(at 106.045 -87.503 -90)
		(property "Reference" "U40"
			(at 1.651 -3.21437 90)
			(unlocked yes)
			(layer "F.SilkS")
			(effects
				(font
					(size 0.7874 0.5842)
					(thickness 0.1524)
				)
			)
		)
		(property "Value" ""
			(at 0 0 270)
			(layer "F.Fab")
			(effects
				(font
					(size 1.27 1.27)
				)
			)
		)
		(property "Device Type" "NLASB3157DFT2G_SC88-G223-10187A"
			(at 0.1524 2.168906 270)
			(unlocked yes)
			(layer "F.Fab")
			(hide yes)
			(effects
				(font
					(size 0.7874 0.5842)
					(thickness 0.000001)
				)
			)
		)
		(property "User Part Number" "PARTNUM*"
			(at 0.127 3.184906 270)
			(unlocked yes)
			(layer "Cmts.User")
			(hide yes)
			(effects
				(font
					(size 0.7874 0.5842)
					(thickness 0.000001)
				)
			)
		)
		(duplicate_pad_numbers_are_jumpers no)
		(fp_line
			(start -1.50876 1.354074)
			(end -1.50876 -1.354074)
			(stroke
				(width 0.1)
				(type default)
			)
			(layer "F.SilkS")
		)
		(fp_line
			(start 1.50876 1.354074)
			(end -1.50876 1.354074)
			(stroke
				(width 0.1)
				(type default)
			)
			(layer "F.SilkS")
		)
		(fp_line
			(start -1.50876 -1.354074)
			(end 1.50876 -1.354074)
			(stroke
				(width 0.1)
				(type default)
			)
			(layer "F.SilkS")
		)
		(fp_line
			(start 1.50876 -1.354074)
			(end 1.50876 1.354074)
			(stroke
				(width 0.1)
				(type default)
			)
			(layer "F.SilkS")
		)
		(fp_poly
			(pts
				(arc
					(start -1.905 -2.159)
					(mid -1.905 -1.397)
					(end -1.905 -2.159)
				)
			)
			(stroke
				(width 0)
				(type default)
			)
			(fill yes)
			(layer "F.SilkS")
		)
		(fp_poly
			(pts
				(xy -1.76276 1.608074) (xy 1.76276 1.608074) (xy 1.76276 -1.608074) (xy -1.76276 -1.608074)
			)
			(stroke
				(width 0)
				(type default)
			)
			(fill no)
			(layer "F.CrtYd")
		)
		(fp_line
			(start -0.674878 1.100074)
			(end -0.674878 -1.100074)
			(stroke
				(width 0.1)
				(type default)
			)
			(layer "F.Fab")
		)
		(fp_line
			(start 0.674878 1.100074)
			(end -0.674878 1.100074)
			(stroke
				(width 0.1)
				(type default)
			)
			(layer "F.Fab")
		)
		(fp_line
			(start -0.674878 -1.100074)
			(end 0.674878 -1.100074)
			(stroke
				(width 0.1)
				(type default)
			)
			(layer "F.Fab")
		)
		(fp_line
			(start 0.674878 -1.100074)
			(end 0.674878 1.100074)
			(stroke
				(width 0.1)
				(type default)
			)
			(layer "F.Fab")
		)
		(fp_poly
			(pts
				(arc
					(start -2.159 -1.3716)
					(mid -2.159 -0.6096)
					(end -2.159 -1.3716)
				)
			)
			(stroke
				(width 0)
				(type default)
			)
			(fill yes)
			(layer "F.Fab")
		)
		(fp_text user "4"
			(at 2.06375 1.27 0)
			(unlocked yes)
			(layer "F.SilkS")
			(effects
				(font
					(size 0.635 0.4064)
					(thickness 0.1524)
				)
			)
		)
		(fp_text user "3"
			(at -2.00025 1.143 0)
			(unlocked yes)
			(layer "F.SilkS")
			(effects
				(font
					(size 0.635 0.4064)
					(thickness 0.1524)
				)
			)
		)
		(fp_text user "6"
			(at 2.06375 -1.27 0)
			(unlocked yes)
			(layer "F.SilkS")
			(effects
				(font
					(size 0.635 0.4064)
					(thickness 0.1524)
				)
			)
		)
		(fp_text user "4"
			(at 2.035048 0.924306 90)
			(unlocked yes)
			(layer "F.Fab")
			(effects
				(font
					(size 0.7874 0.5842)
					(thickness 0.1524)
				)
			)
		)
		(fp_text user "3"
			(at -1.995678 0.91313 90)
			(unlocked yes)
			(layer "F.Fab")
			(effects
				(font
					(size 0.7874 0.5842)
					(thickness 0.1524)
				)
			)
		)
		(fp_text user "6"
			(at 1.97104 -0.731774 90)
			(unlocked yes)
			(layer "F.Fab")
			(effects
				(font
					(size 0.7874 0.5842)
					(thickness 0.1524)
				)
			)
		)
		(pad "1" smd rect
			(at -0.94996 -0.649986 270)
			(size 0.6096 0.4318)
			(layers "F.Cu" "F.Mask" "F.Paste")
			(net "Net_786")
		)
		(pad "2" smd rect
			(at -0.94996 0 270)
			(size 0.6096 0.4318)
			(layers "F.Cu" "F.Mask" "F.Paste")
			(net "SG")
		)
		(pad "3" smd rect
			(at -0.94996 0.649986 270)
			(size 0.6096 0.4318)
			(layers "F.Cu" "F.Mask" "F.Paste")
			(net "FLASH_DQ3")
		)
		(pad "4" smd rect
			(at 0.94996 0.649986 270)
			(size 0.6096 0.4318)
			(layers "F.Cu" "F.Mask" "F.Paste")
			(net "FPGA_FLASH_DQ3")
		)
		(pad "5" smd rect
			(at 0.94996 0 270)
			(size 0.6096 0.4318)
			(layers "F.Cu" "F.Mask" "F.Paste")
			(net "XP3R3V_FPGA")
		)
		(pad "6" smd rect
			(at 0.94996 -0.649986 270)
			(size 0.6096 0.4318)
			(layers "F.Cu" "F.Mask" "F.Paste")
			(net "MUX2_SEL")
		)
	)
	(footprint ""
		(layer "F.Cu")
		(at 94.7166 -72.0598 90)
		(property "Reference" "C194"
			(at 19.8882 -27.49423 90)
			(unlocked yes)
			(layer "F.SilkS")
			(effects
				(font
					(size 0.7874 0.5842)
					(thickness 0.1524)
				)
			)
		)
		(property "Value" "VAL*"
			(at 0.0762 3.134106 90)
			(unlocked yes)
			(layer "F.Fab")
			(hide yes)
			(effects
				(font
					(size 0.7874 0.5842)
					(thickness 0.1524)
				)
			)
		)
		(property "Device Type" "CAPACITOR-G107-0F106-EM,10UF,2A"
			(at 0.0508 2.194306 90)
			(unlocked yes)
			(layer "F.Fab")
			(hide yes)
			(effects
				(font
					(size 0.7874 0.5842)
					(thickness 0.1524)
				)
			)
		)
		(property "User Part Number" "PARTNUM*"
			(at 0.1016 5.013706 90)
			(unlocked yes)
			(layer "Cmts.User")
			(hide yes)
			(effects
				(font
					(size 0.7874 0.5842)
					(thickness 0.1524)
				)
			)
		)
		(property "Tolerance" "TOL*"
			(at 0.0762 4.048506 90)
			(unlocked yes)
			(layer "Cmts.User")
			(hide yes)
			(effects
				(font
					(size 0.7874 0.5842)
					(thickness 0.1524)
				)
			)
		)
		(duplicate_pad_numbers_are_jumpers no)
		(fp_line
			(start 1.5748 -0.9398)
			(end -1.5748 -0.9398)
			(stroke
				(width 0.1)
				(type default)
			)
			(layer "F.SilkS")
		)
		(fp_line
			(start -1.5748 -0.9398)
			(end -1.5748 0.9398)
			(stroke
				(width 0.1)
				(type default)
			)
			(layer "F.SilkS")
		)
		(fp_line
			(start 1.5748 0.9398)
			(end 1.5748 -0.9398)
			(stroke
				(width 0.1)
				(type default)
			)
			(layer "F.SilkS")
		)
		(fp_line
			(start -1.5748 0.9398)
			(end 1.5748 0.9398)
			(stroke
				(width 0.1)
				(type default)
			)
			(layer "F.SilkS")
		)
		(fp_rect
			(start 1.5748 -0.9398)
			(end -1.5748 0.9398)
			(stroke
				(width 0)
				(type default)
			)
			(fill no)
			(layer "F.CrtYd")
		)
		(fp_line
			(start 1.016 -0.635)
			(end -1.016 -0.635)
			(stroke
				(width 0.1)
				(type default)
			)
			(layer "F.Fab")
		)
		(fp_line
			(start -1.016 -0.635)
			(end -1.016 0.635)
			(stroke
				(width 0.1)
				(type default)
			)
			(layer "F.Fab")
		)
		(fp_line
			(start 1.016 0.635)
			(end 1.016 -0.635)
			(stroke
				(width 0.1)
				(type default)
			)
			(layer "F.Fab")
		)
		(fp_line
			(start -1.016 0.635)
			(end 1.016 0.635)
			(stroke
				(width 0.1)
				(type default)
			)
			(layer "F.Fab")
		)
		(pad "1" smd rect
			(at -0.8382 0 90)
			(size 0.9652 1.3716)
			(layers "F.Cu" "F.Mask" "F.Paste")
			(net "XP1R2V_FPGA")
		)
		(pad "2" smd rect
			(at 0.8382 0 90)
			(size 0.9652 1.3716)
			(layers "F.Cu" "F.Mask" "F.Paste")
			(net "SG")
		)
		(zone
			(layer "F.Cu")
			(hatch none 0.5)
			(connect_pads
				(clearance 0)
			)
			(min_thickness 0.25)
			(keepout
				(tracks allowed)
				(vias not_allowed)
				(pads allowed)
				(copperpour not_allowed)
				(footprints allowed)
			)
			(placement
				(enabled no)
				(sheetname "")
			)
			(fill
				(thermal_gap 0.5)
				(thermal_bridge_width 0.5)
				(island_removal_mode 0)
			)
			(polygon
				(pts
					(xy 94.0816 -72.2884) (xy 94.0816 -71.8312) (xy 95.3516 -71.8312) (xy 95.3516 -72.2884)
				)
			)
		)
	)
)
